(kicad_pcb
	(version 20260206)
	(generator "pcbnew")
	(generator_version "10.0")
	(general
		(thickness 1.6)
		(legacy_teardrops no)
	)
	(paper "A4")
	(title_block
		(title "01162023_DA0F0TEBIF0_F0T_Expander_BD_F_brd_V02_OCP.brd")
		(comment 1 "Grand Teton / footprints 1266-1271 of 9728")
	)
	(layers
		(0 "F.Cu" signal "TOP")
		(4 "In1.Cu" signal "GND")
		(6 "In2.Cu" signal "VCC")
		(8 "In3.Cu" signal "VCC1")
		(10 "In4.Cu" signal "GND1")
		(12 "In5.Cu" signal "IN1")
		(14 "In6.Cu" signal "GND2")
		(16 "In7.Cu" signal "IN2")
		(18 "In8.Cu" signal "GND3")
		(20 "In9.Cu" signal "IN3")
		(22 "In10.Cu" signal "GND4")
		(24 "In11.Cu" signal "IN4")
		(26 "In12.Cu" signal "GND5")
		(28 "In13.Cu" signal "IN5")
		(30 "In14.Cu" signal "GND6")
		(32 "In15.Cu" signal "IN6")
		(34 "In16.Cu" signal "GND7")
		(2 "B.Cu" signal "BOTTOM")
		(9 "F.Adhes" user "F.Adhesive")
		(11 "B.Adhes" user "B.Adhesive")
		(13 "F.Paste" user "Package Geometry/Pastemask Top")
		(15 "B.Paste" user "Package Geometry/Pastemask Bottom")
		(5 "F.SilkS" user "Ref Des/Silkscreen Top")
		(7 "B.SilkS" user "Ref Des/Silkscreen Bottom")
		(1 "F.Mask" user "Board Geometry/Soldermask Top")
		(3 "B.Mask" user "Board Geometry/Soldermask Bottom")
		(17 "Dwgs.User" user "User.Drawings")
		(19 "Cmts.User" user "User.Comments")
		(21 "Eco1.User" user "User.Eco1")
		(23 "Eco2.User" user "User.Eco2")
		(25 "Edge.Cuts" user "Board Geometry/Outline")
		(27 "Margin" user)
		(31 "F.CrtYd" user "Package Geometry/Place Bound Top")
		(29 "B.CrtYd" user "Package Geometry/Place Bound Bottom")
		(35 "F.Fab" user "Ref Des/Assembly Top")
		(33 "B.Fab" user "Ref Des/Assembly Bottom")
	)
	(footprint ""
		(layer "F.Cu")
		(at 55.88 -141.9352)
		(property "Reference" "R10"
			(at 0 0 0)
			(layer "F.SilkS")
			(hide yes)
			(effects
				(font
					(size 1.27 1.27)
				)
			)
		)
		(property "Value" ""
			(at 0 0 0)
			(layer "F.Fab")
			(effects
				(font
					(size 1.27 1.27)
				)
			)
		)
		(duplicate_pad_numbers_are_jumpers no)
		(fp_line
			(start -0.7874 -0.4064)
			(end 0.7874 -0.4064)
			(stroke
				(width 0.1524)
				(type default)
			)
			(layer "F.SilkS")
		)
		(fp_line
			(start -0.7874 0.4064)
			(end -0.7874 -0.4064)
			(stroke
				(width 0.1524)
				(type default)
			)
			(layer "F.SilkS")
		)
		(fp_line
			(start 0.7874 -0.4064)
			(end 0.7874 0.4064)
			(stroke
				(width 0.1524)
				(type default)
			)
			(layer "F.SilkS")
		)
		(fp_line
			(start 0.7874 0.4064)
			(end -0.7874 0.4064)
			(stroke
				(width 0.1524)
				(type default)
			)
			(layer "F.SilkS")
		)
		(fp_line
			(start -0.67945 -0.305054)
			(end -0.12065 -0.305054)
			(stroke
				(width 0.1)
				(type default)
			)
			(layer "F.Fab")
		)
		(fp_line
			(start -0.67945 0.3048)
			(end -0.67945 -0.305054)
			(stroke
				(width 0.1)
				(type default)
			)
			(layer "F.Fab")
		)
		(fp_line
			(start -0.12065 -0.305054)
			(end -0.12065 -0.2794)
			(stroke
				(width 0.1)
				(type default)
			)
			(layer "F.Fab")
		)
		(fp_line
			(start -0.12065 -0.2794)
			(end 0.12065 -0.2794)
			(stroke
				(width 0.1)
				(type default)
			)
			(layer "F.Fab")
		)
		(fp_line
			(start -0.12065 0.2794)
			(end -0.12065 0.3048)
			(stroke
				(width 0.1)
				(type default)
			)
			(layer "F.Fab")
		)
		(fp_line
			(start -0.12065 0.3048)
			(end -0.67945 0.3048)
			(stroke
				(width 0.1)
				(type default)
			)
			(layer "F.Fab")
		)
		(fp_line
			(start 0.120396 0.2794)
			(end -0.12065 0.2794)
			(stroke
				(width 0.1)
				(type default)
			)
			(layer "F.Fab")
		)
		(fp_line
			(start 0.120396 0.3048)
			(end 0.120396 0.2794)
			(stroke
				(width 0.1)
				(type default)
			)
			(layer "F.Fab")
		)
		(fp_line
			(start 0.12065 -0.3048)
			(end 0.67945 -0.3048)
			(stroke
				(width 0.1)
				(type default)
			)
			(layer "F.Fab")
		)
		(fp_line
			(start 0.12065 -0.2794)
			(end 0.12065 -0.3048)
			(stroke
				(width 0.1)
				(type default)
			)
			(layer "F.Fab")
		)
		(fp_line
			(start 0.67945 -0.3048)
			(end 0.67945 0.3048)
			(stroke
				(width 0.1)
				(type default)
			)
			(layer "F.Fab")
		)
		(fp_line
			(start 0.67945 0.3048)
			(end 0.120396 0.3048)
			(stroke
				(width 0.1)
				(type default)
			)
			(layer "F.Fab")
		)
		(pad "1" smd circle
			(at -0.40005 0)
			(size 0 0)
			(layers "F.Cu" "F.Mask" "F.Paste")
			(net "SMB_NIC0_R_SDA")
		)
		(pad "2" smd circle
			(at 0.40005 0)
			(size 0 0)
			(layers "F.Cu" "F.Mask" "F.Paste")
			(net "P3V3_NIC0")
		)
	)
	(footprint ""
		(layer "F.Cu")
		(at 445.798448 -66.32194 -90)
		(property "Reference" "PC896"
			(at 0 0 270)
			(layer "F.SilkS")
			(hide yes)
			(effects
				(font
					(size 1.27 1.27)
				)
			)
		)
		(property "Value" ""
			(at 0 0 270)
			(layer "F.Fab")
			(effects
				(font
					(size 1.27 1.27)
				)
			)
		)
		(duplicate_pad_numbers_are_jumpers no)
		(fp_line
			(start -0.7874 0.4064)
			(end -0.7874 -0.4064)
			(stroke
				(width 0.1524)
				(type default)
			)
			(layer "F.SilkS")
		)
		(fp_line
			(start 0.7874 0.4064)
			(end -0.7874 0.4064)
			(stroke
				(width 0.1524)
				(type default)
			)
			(layer "F.SilkS")
		)
		(fp_line
			(start -0.7874 -0.4064)
			(end 0.7874 -0.4064)
			(stroke
				(width 0.1524)
				(type default)
			)
			(layer "F.SilkS")
		)
		(fp_line
			(start 0.7874 -0.4064)
			(end 0.7874 0.4064)
			(stroke
				(width 0.1524)
				(type default)
			)
			(layer "F.SilkS")
		)
		(fp_line
			(start -0.67945 0.3048)
			(end -0.67945 -0.305054)
			(stroke
				(width 0.1)
				(type default)
			)
			(layer "F.Fab")
		)
		(fp_line
			(start -0.12065 0.3048)
			(end -0.67945 0.3048)
			(stroke
				(width 0.1)
				(type default)
			)
			(layer "F.Fab")
		)
		(fp_line
			(start 0.120396 0.3048)
			(end 0.120396 0.2794)
			(stroke
				(width 0.1)
				(type default)
			)
			(layer "F.Fab")
		)
		(fp_line
			(start 0.67945 0.3048)
			(end 0.120396 0.3048)
			(stroke
				(width 0.1)
				(type default)
			)
			(layer "F.Fab")
		)
		(fp_line
			(start -0.12065 0.2794)
			(end -0.12065 0.3048)
			(stroke
				(width 0.1)
				(type default)
			)
			(layer "F.Fab")
		)
		(fp_line
			(start 0.120396 0.2794)
			(end -0.12065 0.2794)
			(stroke
				(width 0.1)
				(type default)
			)
			(layer "F.Fab")
		)
		(fp_line
			(start -0.12065 -0.2794)
			(end 0.12065 -0.2794)
			(stroke
				(width 0.1)
				(type default)
			)
			(layer "F.Fab")
		)
		(fp_line
			(start 0.12065 -0.2794)
			(end 0.12065 -0.3048)
			(stroke
				(width 0.1)
				(type default)
			)
			(layer "F.Fab")
		)
		(fp_line
			(start 0.12065 -0.3048)
			(end 0.67945 -0.3048)
			(stroke
				(width 0.1)
				(type default)
			)
			(layer "F.Fab")
		)
		(fp_line
			(start 0.67945 -0.3048)
			(end 0.67945 0.3048)
			(stroke
				(width 0.1)
				(type default)
			)
			(layer "F.Fab")
		)
		(fp_line
			(start -0.67945 -0.305054)
			(end -0.12065 -0.305054)
			(stroke
				(width 0.1)
				(type default)
			)
			(layer "F.Fab")
		)
		(fp_line
			(start -0.12065 -0.305054)
			(end -0.12065 -0.2794)
			(stroke
				(width 0.1)
				(type default)
			)
			(layer "F.Fab")
		)
		(pad "1" smd circle
			(at -0.40005 0 270)
			(size 0 0)
			(layers "F.Cu" "F.Mask" "F.Paste")
			(net "P12V_SSD15_CO_GATE")
		)
		(pad "2" smd circle
			(at 0.40005 0 270)
			(size 0 0)
			(layers "F.Cu" "F.Mask" "F.Paste")
			(net "GND")
		)
	)
	(footprint ""
		(layer "F.Cu")
		(at 276.147022 -55.63489 90)
		(property "Reference" "PC417"
			(at 0 0 90)
			(layer "F.SilkS")
			(hide yes)
			(effects
				(font
					(size 1.27 1.27)
				)
			)
		)
		(property "Value" ""
			(at 0 0 90)
			(layer "F.Fab")
			(effects
				(font
					(size 1.27 1.27)
				)
			)
		)
		(duplicate_pad_numbers_are_jumpers no)
		(fp_line
			(start 1.524 -0.762)
			(end 1.524 0.762)
			(stroke
				(width 0.1524)
				(type default)
			)
			(layer "F.SilkS")
		)
		(fp_line
			(start -1.524 -0.762)
			(end 1.524 -0.762)
			(stroke
				(width 0.1524)
				(type default)
			)
			(layer "F.SilkS")
		)
		(fp_line
			(start 1.524 0.762)
			(end -1.524 0.762)
			(stroke
				(width 0.1524)
				(type default)
			)
			(layer "F.SilkS")
		)
		(fp_line
			(start -1.524 0.762)
			(end -1.524 -0.762)
			(stroke
				(width 0.1524)
				(type default)
			)
			(layer "F.SilkS")
		)
		(fp_line
			(start 1.1049 -0.724916)
			(end -1.1049 -0.724916)
			(stroke
				(width 0.1)
				(type default)
			)
			(layer "F.Fab")
		)
		(fp_line
			(start -1.1049 -0.724916)
			(end -1.1049 0.724916)
			(stroke
				(width 0.1)
				(type default)
			)
			(layer "F.Fab")
		)
		(fp_line
			(start 1.1049 0.724916)
			(end 1.1049 -0.724916)
			(stroke
				(width 0.1)
				(type default)
			)
			(layer "F.Fab")
		)
		(fp_line
			(start -1.1049 0.724916)
			(end 1.1049 0.724916)
			(stroke
				(width 0.1)
				(type default)
			)
			(layer "F.Fab")
		)
		(pad "1" smd rect
			(at -0.889 0 270)
			(size 1.016 1.27)
			(layers "F.Cu" "F.Mask" "F.Paste")
			(net "P12V_SSD9_R")
		)
		(pad "2" smd rect
			(at 0.889 0 270)
			(size 1.016 1.27)
			(layers "F.Cu" "F.Mask" "F.Paste")
			(net "GND")
		)
	)
	(footprint ""
		(layer "F.Cu")
		(at 358.000046 -209.279236 180)
		(property "Reference" "R5780"
			(at 0 0 180)
			(layer "F.SilkS")
			(hide yes)
			(effects
				(font
					(size 1.27 1.27)
				)
			)
		)
		(property "Value" ""
			(at 0 0 180)
			(layer "F.Fab")
			(effects
				(font
					(size 1.27 1.27)
				)
			)
		)
		(duplicate_pad_numbers_are_jumpers no)
		(fp_line
			(start 0.7874 0.4064)
			(end -0.7874 0.4064)
			(stroke
				(width 0.1524)
				(type default)
			)
			(layer "F.SilkS")
		)
		(fp_line
			(start 0.7874 -0.4064)
			(end 0.7874 0.4064)
			(stroke
				(width 0.1524)
				(type default)
			)
			(layer "F.SilkS")
		)
		(fp_line
			(start -0.7874 0.4064)
			(end -0.7874 -0.4064)
			(stroke
				(width 0.1524)
				(type default)
			)
			(layer "F.SilkS")
		)
		(fp_line
			(start -0.7874 -0.4064)
			(end 0.7874 -0.4064)
			(stroke
				(width 0.1524)
				(type default)
			)
			(layer "F.SilkS")
		)
		(fp_line
			(start 0.67945 0.3048)
			(end 0.120396 0.3048)
			(stroke
				(width 0.1)
				(type default)
			)
			(layer "F.Fab")
		)
		(fp_line
			(start 0.67945 -0.3048)
			(end 0.67945 0.3048)
			(stroke
				(width 0.1)
				(type default)
			)
			(layer "F.Fab")
		)
		(fp_line
			(start 0.12065 -0.2794)
			(end 0.12065 -0.3048)
			(stroke
				(width 0.1)
				(type default)
			)
			(layer "F.Fab")
		)
		(fp_line
			(start 0.12065 -0.3048)
			(end 0.67945 -0.3048)
			(stroke
				(width 0.1)
				(type default)
			)
			(layer "F.Fab")
		)
		(fp_line
			(start 0.120396 0.3048)
			(end 0.120396 0.2794)
			(stroke
				(width 0.1)
				(type default)
			)
			(layer "F.Fab")
		)
		(fp_line
			(start 0.120396 0.2794)
			(end -0.12065 0.2794)
			(stroke
				(width 0.1)
				(type default)
			)
			(layer "F.Fab")
		)
		(fp_line
			(start -0.12065 0.3048)
			(end -0.67945 0.3048)
			(stroke
				(width 0.1)
				(type default)
			)
			(layer "F.Fab")
		)
		(fp_line
			(start -0.12065 0.2794)
			(end -0.12065 0.3048)
			(stroke
				(width 0.1)
				(type default)
			)
			(layer "F.Fab")
		)
		(fp_line
			(start -0.12065 -0.2794)
			(end 0.12065 -0.2794)
			(stroke
				(width 0.1)
				(type default)
			)
			(layer "F.Fab")
		)
		(fp_line
			(start -0.12065 -0.305054)
			(end -0.12065 -0.2794)
			(stroke
				(width 0.1)
				(type default)
			)
			(layer "F.Fab")
		)
		(fp_line
			(start -0.67945 0.3048)
			(end -0.67945 -0.305054)
			(stroke
				(width 0.1)
				(type default)
			)
			(layer "F.Fab")
		)
		(fp_line
			(start -0.67945 -0.305054)
			(end -0.12065 -0.305054)
			(stroke
				(width 0.1)
				(type default)
			)
			(layer "F.Fab")
		)
		(pad "1" smd circle
			(at -0.40005 0 180)
			(size 0 0)
			(layers "F.Cu" "F.Mask" "F.Paste")
			(net "PWRGD_P1V2_AUX_FPGA_R")
		)
		(pad "2" smd circle
			(at 0.40005 0 180)
			(size 0 0)
			(layers "F.Cu" "F.Mask" "F.Paste")
			(net "PWRGD_P1V2_AUX_FPGA")
		)
	)
	(footprint ""
		(layer "F.Cu")
		(at 153.104596 -142.88897 180)
		(property "Reference" "R131"
			(at 0 0 180)
			(layer "F.SilkS")
			(hide yes)
			(effects
				(font
					(size 1.27 1.27)
				)
			)
		)
		(property "Value" ""
			(at 0 0 180)
			(layer "F.Fab")
			(effects
				(font
					(size 1.27 1.27)
				)
			)
		)
		(duplicate_pad_numbers_are_jumpers no)
		(fp_line
			(start 0.7874 0.4064)
			(end -0.7874 0.4064)
			(stroke
				(width 0.1524)
				(type default)
			)
			(layer "F.SilkS")
		)
		(fp_line
			(start 0.7874 -0.4064)
			(end 0.7874 0.4064)
			(stroke
				(width 0.1524)
				(type default)
			)
			(layer "F.SilkS")
		)
		(fp_line
			(start -0.7874 0.4064)
			(end -0.7874 -0.4064)
			(stroke
				(width 0.1524)
				(type default)
			)
			(layer "F.SilkS")
		)
		(fp_line
			(start -0.7874 -0.4064)
			(end 0.7874 -0.4064)
			(stroke
				(width 0.1524)
				(type default)
			)
			(layer "F.SilkS")
		)
		(fp_line
			(start 0.67945 0.3048)
			(end 0.120396 0.3048)
			(stroke
				(width 0.1)
				(type default)
			)
			(layer "F.Fab")
		)
		(fp_line
			(start 0.67945 -0.3048)
			(end 0.67945 0.3048)
			(stroke
				(width 0.1)
				(type default)
			)
			(layer "F.Fab")
		)
		(fp_line
			(start 0.12065 -0.2794)
			(end 0.12065 -0.3048)
			(stroke
				(width 0.1)
				(type default)
			)
			(layer "F.Fab")
		)
		(fp_line
			(start 0.12065 -0.3048)
			(end 0.67945 -0.3048)
			(stroke
				(width 0.1)
				(type default)
			)
			(layer "F.Fab")
		)
		(fp_line
			(start 0.120396 0.3048)
			(end 0.120396 0.2794)
			(stroke
				(width 0.1)
				(type default)
			)
			(layer "F.Fab")
		)
		(fp_line
			(start 0.120396 0.2794)
			(end -0.12065 0.2794)
			(stroke
				(width 0.1)
				(type default)
			)
			(layer "F.Fab")
		)
		(fp_line
			(start -0.12065 0.3048)
			(end -0.67945 0.3048)
			(stroke
				(width 0.1)
				(type default)
			)
			(layer "F.Fab")
		)
		(fp_line
			(start -0.12065 0.2794)
			(end -0.12065 0.3048)
			(stroke
				(width 0.1)
				(type default)
			)
			(layer "F.Fab")
		)
		(fp_line
			(start -0.12065 -0.2794)
			(end 0.12065 -0.2794)
			(stroke
				(width 0.1)
				(type default)
			)
			(layer "F.Fab")
		)
		(fp_line
			(start -0.12065 -0.305054)
			(end -0.12065 -0.2794)
			(stroke
				(width 0.1)
				(type default)
			)
			(layer "F.Fab")
		)
		(fp_line
			(start -0.67945 0.3048)
			(end -0.67945 -0.305054)
			(stroke
				(width 0.1)
				(type default)
			)
			(layer "F.Fab")
		)
		(fp_line
			(start -0.67945 -0.305054)
			(end -0.12065 -0.305054)
			(stroke
				(width 0.1)
				(type default)
			)
			(layer "F.Fab")
		)
		(pad "1" smd circle
			(at -0.40005 0 180)
			(size 0 0)
			(layers "F.Cu" "F.Mask" "F.Paste")
			(net "NIC2_BIF0_N")
		)
		(pad "2" smd circle
			(at 0.40005 0 180)
			(size 0 0)
			(layers "F.Cu" "F.Mask" "F.Paste")
			(net "P3V3_AUX")
		)
	)
	(footprint ""
		(layer "F.Cu")
		(at 358.013 -226.568)
		(property "Reference" "R3623"
			(at 0 0 0)
			(layer "F.SilkS")
			(hide yes)
			(effects
				(font
					(size 1.27 1.27)
				)
			)
		)
		(property "Value" ""
			(at 0 0 0)
			(layer "F.Fab")
			(effects
				(font
					(size 1.27 1.27)
				)
			)
		)
		(duplicate_pad_numbers_are_jumpers no)
		(fp_line
			(start -0.7874 -0.4064)
			(end 0.7874 -0.4064)
			(stroke
				(width 0.1524)
				(type default)
			)
			(layer "F.SilkS")
		)
		(fp_line
			(start -0.7874 0.4064)
			(end -0.7874 -0.4064)
			(stroke
				(width 0.1524)
				(type default)
			)
			(layer "F.SilkS")
		)
		(fp_line
			(start 0.7874 -0.4064)
			(end 0.7874 0.4064)
			(stroke
				(width 0.1524)
				(type default)
			)
			(layer "F.SilkS")
		)
		(fp_line
			(start 0.7874 0.4064)
			(end -0.7874 0.4064)
			(stroke
				(width 0.1524)
				(type default)
			)
			(layer "F.SilkS")
		)
		(fp_line
			(start -0.67945 -0.305054)
			(end -0.12065 -0.305054)
			(stroke
				(width 0.1)
				(type default)
			)
			(layer "F.Fab")
		)
		(fp_line
			(start -0.67945 0.3048)
			(end -0.67945 -0.305054)
			(stroke
				(width 0.1)
				(type default)
			)
			(layer "F.Fab")
		)
		(fp_line
			(start -0.12065 -0.305054)
			(end -0.12065 -0.2794)
			(stroke
				(width 0.1)
				(type default)
			)
			(layer "F.Fab")
		)
		(fp_line
			(start -0.12065 -0.2794)
			(end 0.12065 -0.2794)
			(stroke
				(width 0.1)
				(type default)
			)
			(layer "F.Fab")
		)
		(fp_line
			(start -0.12065 0.2794)
			(end -0.12065 0.3048)
			(stroke
				(width 0.1)
				(type default)
			)
			(layer "F.Fab")
		)
		(fp_line
			(start -0.12065 0.3048)
			(end -0.67945 0.3048)
			(stroke
				(width 0.1)
				(type default)
			)
			(layer "F.Fab")
		)
		(fp_line
			(start 0.120396 0.2794)
			(end -0.12065 0.2794)
			(stroke
				(width 0.1)
				(type default)
			)
			(layer "F.Fab")
		)
		(fp_line
			(start 0.120396 0.3048)
			(end 0.120396 0.2794)
			(stroke
				(width 0.1)
				(type default)
			)
			(layer "F.Fab")
		)
		(fp_line
			(start 0.12065 -0.3048)
			(end 0.67945 -0.3048)
			(stroke
				(width 0.1)
				(type default)
			)
			(layer "F.Fab")
		)
		(fp_line
			(start 0.12065 -0.2794)
			(end 0.12065 -0.3048)
			(stroke
				(width 0.1)
				(type default)
			)
			(layer "F.Fab")
		)
		(fp_line
			(start 0.67945 -0.3048)
			(end 0.67945 0.3048)
			(stroke
				(width 0.1)
				(type default)
			)
			(layer "F.Fab")
		)
		(fp_line
			(start 0.67945 0.3048)
			(end 0.120396 0.3048)
			(stroke
				(width 0.1)
				(type default)
			)
			(layer "F.Fab")
		)
		(pad "1" smd circle
			(at -0.40005 0)
			(size 0 0)
			(layers "F.Cu" "F.Mask" "F.Paste")
			(net "RST_NIC2_PERST_N")
		)
		(pad "2" smd circle
			(at 0.40005 0)
			(size 0 0)
			(layers "F.Cu" "F.Mask" "F.Paste")
			(net "RST_NIC2_PERST_R_N")
		)
	)
)
